(kicad_pcb
	(version 20260206)
	(generator "pcbnew")
	(generator_version "10.0")
	(general
		(thickness 1.6)
		(legacy_teardrops no)
	)
	(paper "A4")
	(title_block
		(title "v2-pdb — ms_pdb_v2.brd")
		(comment 1 "Open CloudServer (Microsoft) / footprints 157-164 of 348")
	)
	(layers
		(0 "F.Cu" signal "TOP")
		(4 "In1.Cu" signal "GND")
		(6 "In2.Cu" signal "IN1")
		(8 "In3.Cu" signal "VCC")
		(10 "In4.Cu" signal "VCC1")
		(12 "In5.Cu" signal "IN2")
		(14 "In6.Cu" signal "GND1")
		(2 "B.Cu" signal "BOTTOM")
		(9 "F.Adhes" user "F.Adhesive")
		(11 "B.Adhes" user "B.Adhesive")
		(13 "F.Paste" user "Package Geometry/Pastemask Top")
		(15 "B.Paste" user "Package Geometry/Pastemask Bottom")
		(5 "F.SilkS" user "Ref Des/Silkscreen Top")
		(7 "B.SilkS" user "Ref Des/Silkscreen Bottom")
		(1 "F.Mask" user "Board Geometry/Soldermask Top")
		(3 "B.Mask" user "Board Geometry/Soldermask Bottom")
		(17 "Dwgs.User" user "User.Drawings")
		(19 "Cmts.User" user "User.Comments")
		(21 "Eco1.User" user "User.Eco1")
		(23 "Eco2.User" user "User.Eco2")
		(25 "Edge.Cuts" user "Board Geometry/Outline")
		(27 "Margin" user)
		(31 "F.CrtYd" user "Package Geometry/Place Bound Top")
		(29 "B.CrtYd" user "Package Geometry/Place Bound Bottom")
		(35 "F.Fab" user "Ref Des/Assembly Top")
		(33 "B.Fab" user "Ref Des/Assembly Bottom")
	)
	(footprint ""
		(layer "F.Cu")
		(at 18.264886 -330.45527 -90)
		(property "Reference" "R34"
			(at 3.685032 -0.234188 90)
			(unlocked yes)
			(layer "F.SilkS")
			(effects
				(font
					(size 0.7874 0.5842)
					(thickness 0.1524)
				)
				(justify left)
			)
		)
		(property "Value" ""
			(at 0 0 270)
			(layer "F.Fab")
			(effects
				(font
					(size 1.27 1.27)
				)
			)
		)
		(duplicate_pad_numbers_are_jumpers no)
		(fp_line
			(start -0.7874 0.4064)
			(end -0.7874 -0.4064)
			(stroke
				(width 0.1524)
				(type default)
			)
			(layer "F.SilkS")
		)
		(fp_line
			(start 0.7874 0.4064)
			(end -0.7874 0.4064)
			(stroke
				(width 0.1524)
				(type default)
			)
			(layer "F.SilkS")
		)
		(fp_line
			(start -0.7874 -0.4064)
			(end 0.7874 -0.4064)
			(stroke
				(width 0.1524)
				(type default)
			)
			(layer "F.SilkS")
		)
		(fp_line
			(start 0.7874 -0.4064)
			(end 0.7874 0.4064)
			(stroke
				(width 0.1524)
				(type default)
			)
			(layer "F.SilkS")
		)
		(fp_poly
			(pts
				(xy -0.508 0.2794) (xy -0.508 0.2286) (xy -0.635 0.2286) (xy -0.635 -0.254) (xy -0.5334 -0.254)
				(xy -0.5334 -0.2794) (xy 0.5334 -0.2794) (xy 0.5334 -0.254) (xy 0.635 -0.254) (xy 0.635 0.254) (xy 0.5334 0.254)
				(xy 0.5334 0.2794)
			)
			(stroke
				(width 0)
				(type default)
			)
			(fill no)
			(layer "F.CrtYd")
		)
		(pad "1" smd rect
			(at 0.40005 0 270)
			(size 0.4572 0.508)
			(layers "F.Cu" "F.Mask" "F.Paste")
			(net "P3V3")
		)
		(pad "2" smd rect
			(at -0.40005 0 270)
			(size 0.4572 0.508)
			(layers "F.Cu" "F.Mask" "F.Paste")
			(net "FRU_A0")
		)
	)
	(footprint ""
		(layer "F.Cu")
		(at 75.151996 -241.518694 -90)
		(property "Reference" "C38"
			(at 0.73406 -3.85445 90)
			(unlocked yes)
			(layer "F.SilkS")
			(effects
				(font
					(size 0.7874 0.5842)
					(thickness 0.1524)
				)
				(justify left)
			)
		)
		(property "Value" ""
			(at 0 0 270)
			(layer "F.Fab")
			(effects
				(font
					(size 1.27 1.27)
				)
			)
		)
		(duplicate_pad_numbers_are_jumpers no)
		(fp_line
			(start -0.7874 0.4064)
			(end -0.7874 -0.4064)
			(stroke
				(width 0.1524)
				(type default)
			)
			(layer "F.SilkS")
		)
		(fp_line
			(start 0.7874 0.4064)
			(end -0.7874 0.4064)
			(stroke
				(width 0.1524)
				(type default)
			)
			(layer "F.SilkS")
		)
		(fp_line
			(start 0 0.381)
			(end 0 -0.381)
			(stroke
				(width 0.1524)
				(type default)
			)
			(layer "F.SilkS")
		)
		(fp_line
			(start -0.7874 -0.4064)
			(end 0.7874 -0.4064)
			(stroke
				(width 0.1524)
				(type default)
			)
			(layer "F.SilkS")
		)
		(fp_line
			(start 0.7874 -0.4064)
			(end 0.7874 0.4064)
			(stroke
				(width 0.1524)
				(type default)
			)
			(layer "F.SilkS")
		)
		(fp_poly
			(pts
				(xy -0.5334 0.254) (xy -0.635 0.254) (xy -0.635 0.2286) (xy -0.635 -0.254) (xy -0.5334 -0.254) (xy -0.5334 -0.2794)
				(xy 0.5334 -0.2794) (xy 0.5334 -0.254) (xy 0.635 -0.254) (xy 0.635 0.254) (xy 0.5334 0.254) (xy 0.5334 0.2794)
				(xy -0.508 0.2794) (xy -0.5334 0.2794)
			)
			(stroke
				(width 0)
				(type default)
			)
			(fill no)
			(layer "F.CrtYd")
		)
		(pad "1" smd rect
			(at 0.40005 0 270)
			(size 0.4572 0.508)
			(layers "F.Cu" "F.Mask" "F.Paste")
			(net "P12V")
		)
		(pad "2" smd rect
			(at -0.40005 0 270)
			(size 0.4572 0.508)
			(layers "F.Cu" "F.Mask" "F.Paste")
			(net "GND")
		)
	)
	(footprint ""
		(layer "F.Cu")
		(at 14.923008 -330.497434 -90)
		(property "Reference" "R35"
			(at 3.685032 -0.234188 90)
			(unlocked yes)
			(layer "F.SilkS")
			(effects
				(font
					(size 0.7874 0.5842)
					(thickness 0.1524)
				)
				(justify left)
			)
		)
		(property "Value" ""
			(at 0 0 270)
			(layer "F.Fab")
			(effects
				(font
					(size 1.27 1.27)
				)
			)
		)
		(duplicate_pad_numbers_are_jumpers no)
		(fp_line
			(start -0.7874 0.4064)
			(end -0.7874 -0.4064)
			(stroke
				(width 0.1524)
				(type default)
			)
			(layer "F.SilkS")
		)
		(fp_line
			(start 0.7874 0.4064)
			(end -0.7874 0.4064)
			(stroke
				(width 0.1524)
				(type default)
			)
			(layer "F.SilkS")
		)
		(fp_line
			(start -0.7874 -0.4064)
			(end 0.7874 -0.4064)
			(stroke
				(width 0.1524)
				(type default)
			)
			(layer "F.SilkS")
		)
		(fp_line
			(start 0.7874 -0.4064)
			(end 0.7874 0.4064)
			(stroke
				(width 0.1524)
				(type default)
			)
			(layer "F.SilkS")
		)
		(fp_poly
			(pts
				(xy -0.508 0.2794) (xy -0.508 0.2286) (xy -0.635 0.2286) (xy -0.635 -0.254) (xy -0.5334 -0.254)
				(xy -0.5334 -0.2794) (xy 0.5334 -0.2794) (xy 0.5334 -0.254) (xy 0.635 -0.254) (xy 0.635 0.254) (xy 0.5334 0.254)
				(xy 0.5334 0.2794)
			)
			(stroke
				(width 0)
				(type default)
			)
			(fill no)
			(layer "F.CrtYd")
		)
		(pad "1" smd rect
			(at 0.40005 0 270)
			(size 0.4572 0.508)
			(layers "F.Cu" "F.Mask" "F.Paste")
			(net "P3V3")
		)
		(pad "2" smd rect
			(at -0.40005 0 270)
			(size 0.4572 0.508)
			(layers "F.Cu" "F.Mask" "F.Paste")
			(net "FRU_A1")
		)
	)
	(footprint ""
		(layer "F.Cu")
		(at 50.284126 -395.548358 180)
		(property "Reference" "CE18"
			(at -3.83413 -2.721864 0)
			(unlocked yes)
			(layer "F.SilkS")
			(effects
				(font
					(size 0.7874 0.5842)
					(thickness 0.1524)
				)
				(justify left)
			)
		)
		(property "Value" ""
			(at 0 0 180)
			(layer "F.Fab")
			(effects
				(font
					(size 1.27 1.27)
				)
			)
		)
		(duplicate_pad_numbers_are_jumpers no)
		(fp_line
			(start 0 -4.2672)
			(end 0 4.2672)
			(stroke
				(width 0.1524)
				(type default)
			)
			(layer "F.SilkS")
		)
		(fp_circle
			(center 0 0)
			(end -4.2672 0)
			(stroke
				(width 0.1524)
				(type default)
			)
			(fill no)
			(layer "F.SilkS")
		)
		(fp_poly
			(pts
				(arc
					(start 0 -4.2672)
					(mid 4.2672 0)
					(end 0 4.2672)
				)
			)
			(stroke
				(width 0)
				(type default)
			)
			(fill yes)
			(layer "F.SilkS")
		)
		(fp_poly
			(pts
				(xy -2.5146 -0.762) (xy -0.9906 -0.762) (xy -0.9906 0.762) (xy -2.5146 0.762)
			)
			(stroke
				(width 0)
				(type default)
			)
			(fill no)
			(layer "B.CrtYd")
		)
		(fp_poly
			(pts
				(arc
					(start 1.7526 0.762)
					(mid 2.291415 -0.538815)
					(end 0.9906 0)
				)
				(arc
					(start 0.9906 0.0254)
					(mid 1.206345 0.546255)
					(end 1.7272 0.762)
				)
			)
			(stroke
				(width 0)
				(type default)
			)
			(fill no)
			(layer "B.CrtYd")
		)
		(fp_poly
			(pts
				(arc
					(start -4.2672 0)
					(mid 4.2672 0)
					(end -4.2672 0)
				)
			)
			(stroke
				(width 0)
				(type default)
			)
			(fill no)
			(layer "F.CrtYd")
		)
		(fp_circle
			(center 0 0)
			(end -4.2672 0)
			(stroke
				(width 0.1)
				(type default)
			)
			(fill no)
			(layer "F.Fab")
		)
		(fp_text user "+"
			(at -5.834634 -1.153414 180)
			(unlocked yes)
			(layer "F.SilkS")
			(effects
				(font
					(size 1.905 1.4224)
					(thickness 0.1524)
				)
				(justify left)
			)
		)
		(fp_text user "+"
			(at -5.6642 -0.34925 180)
			(unlocked yes)
			(layer "F.Fab")
			(effects
				(font
					(size 1.905 1.4224)
					(thickness 0.000001)
				)
				(justify left)
			)
		)
		(pad "1" thru_hole rect
			(at -1.75006 0 180)
			(size 1.397 1.397)
			(drill 0.9144)
			(layers "*.Cu" "*.Mask")
			(remove_unused_layers no)
			(net "P12V")
			(clearance 0.0127)
			(thermal_gap 0.0127)
			(padstack
				(mode front_inner_back)
				(layer "Inner"
					(shape circle)
					(size 1.397 1.397)
					(clearance 0.0127)
				)
				(layer "B.Cu"
					(shape rect)
					(size 1.397 1.397)
					(clearance 0.0127)
				)
			)
		)
		(pad "2" thru_hole circle
			(at 1.75006 0 180)
			(size 1.397 1.397)
			(drill 0.9144)
			(layers "*.Cu" "*.Mask")
			(remove_unused_layers no)
			(net "GND")
			(clearance 0.0127)
			(thermal_gap 0.0127)
		)
	)
	(footprint ""
		(layer "F.Cu")
		(at 13.853922 -330.480924 -90)
		(property "Reference" "R39"
			(at 3.685032 -0.234188 90)
			(unlocked yes)
			(layer "F.SilkS")
			(effects
				(font
					(size 0.7874 0.5842)
					(thickness 0.1524)
				)
				(justify left)
			)
		)
		(property "Value" ""
			(at 0 0 270)
			(layer "F.Fab")
			(effects
				(font
					(size 1.27 1.27)
				)
			)
		)
		(duplicate_pad_numbers_are_jumpers no)
		(fp_line
			(start -0.7874 0.4064)
			(end -0.7874 -0.4064)
			(stroke
				(width 0.1524)
				(type default)
			)
			(layer "F.SilkS")
		)
		(fp_line
			(start 0.7874 0.4064)
			(end -0.7874 0.4064)
			(stroke
				(width 0.1524)
				(type default)
			)
			(layer "F.SilkS")
		)
		(fp_line
			(start -0.7874 -0.4064)
			(end 0.7874 -0.4064)
			(stroke
				(width 0.1524)
				(type default)
			)
			(layer "F.SilkS")
		)
		(fp_line
			(start 0.7874 -0.4064)
			(end 0.7874 0.4064)
			(stroke
				(width 0.1524)
				(type default)
			)
			(layer "F.SilkS")
		)
		(fp_poly
			(pts
				(xy -0.508 0.2794) (xy -0.508 0.2286) (xy -0.635 0.2286) (xy -0.635 -0.254) (xy -0.5334 -0.254)
				(xy -0.5334 -0.2794) (xy 0.5334 -0.2794) (xy 0.5334 -0.254) (xy 0.635 -0.254) (xy 0.635 0.254) (xy 0.5334 0.254)
				(xy 0.5334 0.2794)
			)
			(stroke
				(width 0)
				(type default)
			)
			(fill no)
			(layer "F.CrtYd")
		)
		(pad "1" smd rect
			(at 0.40005 0 270)
			(size 0.4572 0.508)
			(layers "F.Cu" "F.Mask" "F.Paste")
			(net "GND")
		)
		(pad "2" smd rect
			(at -0.40005 0 270)
			(size 0.4572 0.508)
			(layers "F.Cu" "F.Mask" "F.Paste")
			(net "FRU_A2")
		)
	)
	(footprint ""
		(layer "F.Cu")
		(at 39.979854 -375.988326 180)
		(property "Reference" "R14"
			(at -2.032762 0.011938 0)
			(unlocked yes)
			(layer "F.SilkS")
			(effects
				(font
					(size 0.7874 0.5842)
					(thickness 0.1524)
				)
				(justify left)
			)
		)
		(property "Value" ""
			(at 0 0 180)
			(layer "F.Fab")
			(effects
				(font
					(size 1.27 1.27)
				)
			)
		)
		(duplicate_pad_numbers_are_jumpers no)
		(fp_line
			(start 0.7874 0.4064)
			(end -0.7874 0.4064)
			(stroke
				(width 0.1524)
				(type default)
			)
			(layer "F.SilkS")
		)
		(fp_line
			(start 0.7874 -0.4064)
			(end 0.7874 0.4064)
			(stroke
				(width 0.1524)
				(type default)
			)
			(layer "F.SilkS")
		)
		(fp_line
			(start -0.7874 0.4064)
			(end -0.7874 -0.4064)
			(stroke
				(width 0.1524)
				(type default)
			)
			(layer "F.SilkS")
		)
		(fp_line
			(start -0.7874 -0.4064)
			(end 0.7874 -0.4064)
			(stroke
				(width 0.1524)
				(type default)
			)
			(layer "F.SilkS")
		)
		(fp_poly
			(pts
				(xy -0.508 0.2794) (xy -0.508 0.2286) (xy -0.635 0.2286) (xy -0.635 -0.254) (xy -0.5334 -0.254)
				(xy -0.5334 -0.2794) (xy 0.5334 -0.2794) (xy 0.5334 -0.254) (xy 0.635 -0.254) (xy 0.635 0.254) (xy 0.5334 0.254)
				(xy 0.5334 0.2794)
			)
			(stroke
				(width 0)
				(type default)
			)
			(fill no)
			(layer "F.CrtYd")
		)
		(pad "1" smd rect
			(at 0.40005 0 180)
			(size 0.4572 0.508)
			(layers "F.Cu" "F.Mask" "F.Paste")
			(net "PSU5_REMOTE_P")
		)
		(pad "2" smd rect
			(at -0.40005 0 180)
			(size 0.4572 0.508)
			(layers "F.Cu" "F.Mask" "F.Paste")
			(net "P12V")
		)
	)
	(footprint ""
		(layer "F.Cu")
		(at 77.999844 -478.300034)
		(property "Reference" "H13"
			(at -3.29692 -5.248656 0)
			(unlocked yes)
			(layer "F.SilkS")
			(effects
				(font
					(size 0.7874 0.5842)
					(thickness 0.1524)
				)
				(justify left)
			)
		)
		(property "Value" ""
			(at 0 0 0)
			(layer "F.Fab")
			(effects
				(font
					(size 1.27 1.27)
				)
			)
		)
		(duplicate_pad_numbers_are_jumpers no)
		(fp_line
			(start -3.4163 0)
			(end -3.4163 -0.4953)
			(stroke
				(width 0.1524)
				(type default)
			)
			(layer "F.SilkS")
		)
		(fp_line
			(start -3.4163 0.4953)
			(end -3.4163 0)
			(stroke
				(width 0.1524)
				(type default)
			)
			(layer "F.SilkS")
		)
		(fp_line
			(start 3.4163 -0.4953)
			(end 3.4163 0.4953)
			(stroke
				(width 0.1524)
				(type default)
			)
			(layer "F.SilkS")
		)
		(fp_arc
			(start -3.4163 -0.4953)
			(mid -2.415689 -2.910989)
			(end 0 -3.9116)
			(stroke
				(width 0.1524)
				(type default)
			)
			(layer "F.SilkS")
		)
		(fp_arc
			(start 0 -3.9116)
			(mid 2.415689 -2.910989)
			(end 3.4163 -0.4953)
			(stroke
				(width 0.1524)
				(type default)
			)
			(layer "F.SilkS")
		)
		(fp_arc
			(start 0 3.9116)
			(mid -2.415689 2.910989)
			(end -3.4163 0.4953)
			(stroke
				(width 0.1524)
				(type default)
			)
			(layer "F.SilkS")
		)
		(fp_arc
			(start 3.4163 0.4953)
			(mid 2.415689 2.910989)
			(end 0 3.9116)
			(stroke
				(width 0.1524)
				(type default)
			)
			(layer "F.SilkS")
		)
		(fp_line
			(start -3.4163 0)
			(end -3.4163 -0.4953)
			(stroke
				(width 0.1524)
				(type default)
			)
			(layer "B.SilkS")
		)
		(fp_line
			(start -3.4163 0.4953)
			(end -3.4163 0)
			(stroke
				(width 0.1524)
				(type default)
			)
			(layer "B.SilkS")
		)
		(fp_line
			(start 3.4163 -0.4953)
			(end 3.4163 0.4953)
			(stroke
				(width 0.1524)
				(type default)
			)
			(layer "B.SilkS")
		)
		(fp_arc
			(start -3.4163 -0.4953)
			(mid -2.415689 -2.910989)
			(end 0 -3.9116)
			(stroke
				(width 0.1524)
				(type default)
			)
			(layer "B.SilkS")
		)
		(fp_arc
			(start 0 -3.9116)
			(mid 2.415689 -2.910989)
			(end 3.4163 -0.4953)
			(stroke
				(width 0.1524)
				(type default)
			)
			(layer "B.SilkS")
		)
		(fp_arc
			(start 0 3.9116)
			(mid -2.415689 2.910989)
			(end -3.4163 0.4953)
			(stroke
				(width 0.1524)
				(type default)
			)
			(layer "B.SilkS")
		)
		(fp_arc
			(start 3.4163 0.4953)
			(mid 2.415689 2.910989)
			(end 0 3.9116)
			(stroke
				(width 0.1524)
				(type default)
			)
			(layer "B.SilkS")
		)
		(fp_poly
			(pts
				(arc
					(start -2.853944 -0.499872)
					(mid 0 -3.353816)
					(end 2.853944 -0.499872)
				)
				(arc
					(start 2.853944 0.499872)
					(mid 0 3.35407)
					(end -2.853944 0.499872)
				)
			)
			(stroke
				(width 0)
				(type default)
			)
			(fill no)
			(layer "B.CrtYd")
		)
		(fp_poly
			(pts
				(arc
					(start -2.853944 -0.499872)
					(mid 0 -3.353816)
					(end 2.853944 -0.499872)
				)
				(arc
					(start 2.853944 0.499872)
					(mid 0 3.35407)
					(end -2.853944 0.499872)
				)
			)
			(stroke
				(width 0)
				(type default)
			)
			(fill no)
			(layer "F.CrtYd")
		)
		(pad "" np_thru_hole oval
			(at 0 0)
			(size 5.207 6.1976)
			(drill oval 5.207 6.1976)
			(layers "*.Cu" "*.Mask")
			(clearance 0.381)
			(thermal_gap 0.381)
		)
		(zone
			(layers "F.Cu" "B.Cu" "In1.Cu" "In2.Cu" "In3.Cu" "In4.Cu" "In5.Cu" "In6.Cu")
			(hatch none 0.5)
			(connect_pads
				(clearance 0)
			)
			(min_thickness 0.25)
			(keepout
				(tracks not_allowed)
				(vias allowed)
				(pads allowed)
				(copperpour not_allowed)
				(footprints allowed)
			)
			(placement
				(enabled no)
				(sheetname "")
			)
			(fill
				(thermal_gap 0.5)
				(thermal_bridge_width 0.5)
				(island_removal_mode 0)
			)
			(polygon
				(pts
					(xy 74.888344 -478.300034)
					(arc
						(start 74.888344 -478.795334)
						(mid 75.799681 -480.995497)
						(end 77.999844 -481.906834)
					)
					(arc
						(start 77.999844 -481.906834)
						(mid 80.200007 -480.995497)
						(end 81.111344 -478.795334)
					)
					(arc
						(start 81.111344 -477.804734)
						(mid 80.200007 -475.604571)
						(end 77.999844 -474.693234)
					)
					(arc
						(start 77.999844 -474.693234)
						(mid 75.799681 -475.604571)
						(end 74.888344 -477.804734)
					)
				)
			)
		)
	)
	(footprint ""
		(layer "F.Cu")
		(at 71.815198 -197.392544 -90)
		(property "Reference" "C31"
			(at 3.603498 -0.336804 90)
			(unlocked yes)
			(layer "F.SilkS")
			(effects
				(font
					(size 0.7874 0.5842)
					(thickness 0.1524)
				)
				(justify left)
			)
		)
		(property "Value" ""
			(at 0 0 270)
			(layer "F.Fab")
			(effects
				(font
					(size 1.27 1.27)
				)
			)
		)
		(duplicate_pad_numbers_are_jumpers no)
		(fp_line
			(start -0.7874 0.4064)
			(end -0.7874 -0.4064)
			(stroke
				(width 0.1524)
				(type default)
			)
			(layer "F.SilkS")
		)
		(fp_line
			(start 0.7874 0.4064)
			(end -0.7874 0.4064)
			(stroke
				(width 0.1524)
				(type default)
			)
			(layer "F.SilkS")
		)
		(fp_line
			(start 0 0.381)
			(end 0 -0.381)
			(stroke
				(width 0.1524)
				(type default)
			)
			(layer "F.SilkS")
		)
		(fp_line
			(start -0.7874 -0.4064)
			(end 0.7874 -0.4064)
			(stroke
				(width 0.1524)
				(type default)
			)
			(layer "F.SilkS")
		)
		(fp_line
			(start 0.7874 -0.4064)
			(end 0.7874 0.4064)
			(stroke
				(width 0.1524)
				(type default)
			)
			(layer "F.SilkS")
		)
		(fp_poly
			(pts
				(xy -0.5334 0.254) (xy -0.635 0.254) (xy -0.635 0.2286) (xy -0.635 -0.254) (xy -0.5334 -0.254) (xy -0.5334 -0.2794)
				(xy 0.5334 -0.2794) (xy 0.5334 -0.254) (xy 0.635 -0.254) (xy 0.635 0.254) (xy 0.5334 0.254) (xy 0.5334 0.2794)
				(xy -0.508 0.2794) (xy -0.5334 0.2794)
			)
			(stroke
				(width 0)
				(type default)
			)
			(fill no)
			(layer "F.CrtYd")
		)
		(pad "1" smd rect
			(at 0.40005 0 270)
			(size 0.4572 0.508)
			(layers "F.Cu" "F.Mask" "F.Paste")
			(net "P12V")
		)
		(pad "2" smd rect
			(at -0.40005 0 270)
			(size 0.4572 0.508)
			(layers "F.Cu" "F.Mask" "F.Paste")
			(net "GND")
		)
	)
)
